# SCM (Grand Teton) — schematic netlist excerpt (pin names and nets, part order shuffled) for the footprints in the layout excerpt that follows; sources: Cadence DE-HDL packaged netlist, KiCad conversion of 12092022_DA0F0TMDCD0_F0T_Management_Board_D_brd_V3_OCP.brd

R231  Q_RES  0 5% CHIP  pkg 0402LF  page 17 : A = P3V3_AUX ; B = P3V3_P1V8_I2C_I3C
R109  Q_RES  0 5% CHIP  pkg 0402LF  page 46 : A = SPI_BMC_TPM_CLK_R ; B = SPI_BMC_TPM_CLK

(kicad_pcb
	(version 20260206)
	(generator "pcbnew")
	(generator_version "10.0")
	(general
		(thickness 1.6)
		(legacy_teardrops no)
	)
	(paper "A4")
	(title_block
		(title "12092022_DA0F0TMDCD0_F0T_Management_Board_D_brd_V3_OCP.brd")
		(comment 1 "Grand Teton / footprints 412-413 of 1440")
	)
	(layers
		(0 "F.Cu" signal "TOP")
		(4 "In1.Cu" signal "GND")
		(6 "In2.Cu" signal "IN1")
		(8 "In3.Cu" signal "GND1")
		(10 "In4.Cu" signal "IN2")
		(12 "In5.Cu" signal "VCC")
		(14 "In6.Cu" signal "VCC1")
		(16 "In7.Cu" signal "IN3")
		(18 "In8.Cu" signal "GND2")
		(20 "In9.Cu" signal "IN4")
		(22 "In10.Cu" signal "GND3")
		(2 "B.Cu" signal "BOTTOM")
		(9 "F.Adhes" user "F.Adhesive")
		(11 "B.Adhes" user "B.Adhesive")
		(13 "F.Paste" user "Package Geometry/Pastemask Top")
		(15 "B.Paste" user "Package Geometry/Pastemask Bottom")
		(5 "F.SilkS" user "Ref Des/Silkscreen Top")
		(7 "B.SilkS" user "Ref Des/Silkscreen Bottom")
		(1 "F.Mask" user "Board Geometry/Soldermask Top")
		(3 "B.Mask" user "Board Geometry/Soldermask Bottom")
		(17 "Dwgs.User" user "User.Drawings")
		(19 "Cmts.User" user "User.Comments")
		(21 "Eco1.User" user "User.Eco1")
		(23 "Eco2.User" user "User.Eco2")
		(25 "Edge.Cuts" user "Board Geometry/Outline")
		(27 "Margin" user)
		(31 "F.CrtYd" user "Package Geometry/Place Bound Top")
		(29 "B.CrtYd" user "Package Geometry/Place Bound Bottom")
		(35 "F.Fab" user "Ref Des/Assembly Top")
		(33 "B.Fab" user "Ref Des/Assembly Bottom")
	)
	(footprint ""
		(layer "F.Cu")
		(at 84.201 -92.202)
		(property "Reference" "R109"
			(at 0 0 0)
			(layer "F.SilkS")
			(hide yes)
			(effects
				(font
					(size 1.27 1.27)
				)
			)
		)
		(property "Value" ""
			(at 0 0 0)
			(layer "F.Fab")
			(effects
				(font
					(size 1.27 1.27)
				)
			)
		)
		(duplicate_pad_numbers_are_jumpers no)
		(fp_line
			(start -0.7874 -0.4064)
			(end 0.7874 -0.4064)
			(stroke
				(width 0.1524)
				(type default)
			)
			(layer "F.SilkS")
		)
		(fp_line
			(start -0.7874 0.4064)
			(end -0.7874 -0.4064)
			(stroke
				(width 0.1524)
				(type default)
			)
			(layer "F.SilkS")
		)
		(fp_line
			(start 0.7874 -0.4064)
			(end 0.7874 0.4064)
			(stroke
				(width 0.1524)
				(type default)
			)
			(layer "F.SilkS")
		)
		(fp_line
			(start 0.7874 0.4064)
			(end -0.7874 0.4064)
			(stroke
				(width 0.1524)
				(type default)
			)
			(layer "F.SilkS")
		)
		(fp_line
			(start -0.67945 -0.305054)
			(end -0.12065 -0.305054)
			(stroke
				(width 0.1)
				(type default)
			)
			(layer "F.Fab")
		)
		(fp_line
			(start -0.67945 0.3048)
			(end -0.67945 -0.305054)
			(stroke
				(width 0.1)
				(type default)
			)
			(layer "F.Fab")
		)
		(fp_line
			(start -0.12065 -0.305054)
			(end -0.12065 -0.2794)
			(stroke
				(width 0.1)
				(type default)
			)
			(layer "F.Fab")
		)
		(fp_line
			(start -0.12065 -0.2794)
			(end 0.12065 -0.2794)
			(stroke
				(width 0.1)
				(type default)
			)
			(layer "F.Fab")
		)
		(fp_line
			(start -0.12065 0.2794)
			(end -0.12065 0.3048)
			(stroke
				(width 0.1)
				(type default)
			)
			(layer "F.Fab")
		)
		(fp_line
			(start -0.12065 0.3048)
			(end -0.67945 0.3048)
			(stroke
				(width 0.1)
				(type default)
			)
			(layer "F.Fab")
		)
		(fp_line
			(start 0.120396 0.2794)
			(end -0.12065 0.2794)
			(stroke
				(width 0.1)
				(type default)
			)
			(layer "F.Fab")
		)
		(fp_line
			(start 0.120396 0.3048)
			(end 0.120396 0.2794)
			(stroke
				(width 0.1)
				(type default)
			)
			(layer "F.Fab")
		)
		(fp_line
			(start 0.12065 -0.3048)
			(end 0.67945 -0.3048)
			(stroke
				(width 0.1)
				(type default)
			)
			(layer "F.Fab")
		)
		(fp_line
			(start 0.12065 -0.2794)
			(end 0.12065 -0.3048)
			(stroke
				(width 0.1)
				(type default)
			)
			(layer "F.Fab")
		)
		(fp_line
			(start 0.67945 -0.3048)
			(end 0.67945 0.3048)
			(stroke
				(width 0.1)
				(type default)
			)
			(layer "F.Fab")
		)
		(fp_line
			(start 0.67945 0.3048)
			(end 0.120396 0.3048)
			(stroke
				(width 0.1)
				(type default)
			)
			(layer "F.Fab")
		)
		(pad "1" smd circle
			(at -0.40005 0)
			(size 0 0)
			(layers "F.Cu" "F.Mask" "F.Paste")
			(net "SPI_BMC_TPM_CLK_R")
		)
		(pad "2" smd circle
			(at 0.40005 0)
			(size 0 0)
			(layers "F.Cu" "F.Mask" "F.Paste")
			(net "SPI_BMC_TPM_CLK")
		)
	)
	(footprint ""
		(layer "F.Cu")
		(at 36.957 -36.068 -90)
		(property "Reference" "R231"
			(at 0 0 270)
			(layer "F.SilkS")
			(hide yes)
			(effects
				(font
					(size 1.27 1.27)
				)
			)
		)
		(property "Value" ""
			(at 0 0 270)
			(layer "F.Fab")
			(effects
				(font
					(size 1.27 1.27)
				)
			)
		)
		(duplicate_pad_numbers_are_jumpers no)
		(fp_line
			(start -0.7874 0.4064)
			(end -0.7874 -0.4064)
			(stroke
				(width 0.1524)
				(type default)
			)
			(layer "F.SilkS")
		)
		(fp_line
			(start 0.7874 0.4064)
			(end -0.7874 0.4064)
			(stroke
				(width 0.1524)
				(type default)
			)
			(layer "F.SilkS")
		)
		(fp_line
			(start -0.7874 -0.4064)
			(end 0.7874 -0.4064)
			(stroke
				(width 0.1524)
				(type default)
			)
			(layer "F.SilkS")
		)
		(fp_line
			(start 0.7874 -0.4064)
			(end 0.7874 0.4064)
			(stroke
				(width 0.1524)
				(type default)
			)
			(layer "F.SilkS")
		)
		(fp_line
			(start -0.67945 0.3048)
			(end -0.67945 -0.305054)
			(stroke
				(width 0.1)
				(type default)
			)
			(layer "F.Fab")
		)
		(fp_line
			(start -0.12065 0.3048)
			(end -0.67945 0.3048)
			(stroke
				(width 0.1)
				(type default)
			)
			(layer "F.Fab")
		)
		(fp_line
			(start 0.120396 0.3048)
			(end 0.120396 0.2794)
			(stroke
				(width 0.1)
				(type default)
			)
			(layer "F.Fab")
		)
		(fp_line
			(start 0.67945 0.3048)
			(end 0.120396 0.3048)
			(stroke
				(width 0.1)
				(type default)
			)
			(layer "F.Fab")
		)
		(fp_line
			(start -0.12065 0.2794)
			(end -0.12065 0.3048)
			(stroke
				(width 0.1)
				(type default)
			)
			(layer "F.Fab")
		)
		(fp_line
			(start 0.120396 0.2794)
			(end -0.12065 0.2794)
			(stroke
				(width 0.1)
				(type default)
			)
			(layer "F.Fab")
		)
		(fp_line
			(start -0.12065 -0.2794)
			(end 0.12065 -0.2794)
			(stroke
				(width 0.1)
				(type default)
			)
			(layer "F.Fab")
		)
		(fp_line
			(start 0.12065 -0.2794)
			(end 0.12065 -0.3048)
			(stroke
				(width 0.1)
				(type default)
			)
			(layer "F.Fab")
		)
		(fp_line
			(start 0.12065 -0.3048)
			(end 0.67945 -0.3048)
			(stroke
				(width 0.1)
				(type default)
			)
			(layer "F.Fab")
		)
		(fp_line
			(start 0.67945 -0.3048)
			(end 0.67945 0.3048)
			(stroke
				(width 0.1)
				(type default)
			)
			(layer "F.Fab")
		)
		(fp_line
			(start -0.67945 -0.305054)
			(end -0.12065 -0.305054)
			(stroke
				(width 0.1)
				(type default)
			)
			(layer "F.Fab")
		)
		(fp_line
			(start -0.12065 -0.305054)
			(end -0.12065 -0.2794)
			(stroke
				(width 0.1)
				(type default)
			)
			(layer "F.Fab")
		)
		(pad "1" smd circle
			(at -0.40005 0 270)
			(size 0 0)
			(layers "F.Cu" "F.Mask" "F.Paste")
			(net "P3V3_AUX")
		)
		(pad "2" smd circle
			(at 0.40005 0 270)
			(size 0 0)
			(layers "F.Cu" "F.Mask" "F.Paste")
			(net "P3V3_P1V8_I2C_I3C")
		)
	)
)
